FILE_TYPE = MULTI_PHYS_TABLE;

PART 'Q_SHORT'

{========================================================================================}
:PACK_TYPE | MATERIAL | PART_NUMBER    = STANDARD | LIFECYCLE | PART_NUMBER | JEDEC_TYPE                      | CLASS | DESCRIPTION                     | HEIGHT | COMPONENT_TYPE | LEAD_LENGTH | DFM_EXCLUSION | I_PN | FROM_PJ       | LEAD_FREE ;
{========================================================================================}
 'SM'      | 'EMPTY'  | 'SHORT-C1'(!)  = ''       | ''        | 'SHORT-C1'  |'SHORT80X104'| 'IO'  | 'JUMP,SHORT80X104'              | ''     | ''             | ''          | ''            | ''   | 'T73-CT'      | ''       
 'SM'      | 'EMPTY'  | 'SHORT6'(!)    = ''       | ''        | 'SHORT6'    |'SHORT_R0603'| 'IO'  | 'JUMP,SHORT_R0603'              | ''     | ''             | ''          | ''            | ''   | 'T73-CT'      | ''       
 'SM'      | 'EMPTY'  | 'SHORT7'(!)    = ''       | ''        | 'SHORT7'    |'SHORT_R0402'| 'IO'  | 'JUMP,SHORT_R0402'              | ''     | ''             | ''          | ''            | ''   | 'T73-CT'      | ''       
 'SM'      | 'EMPTY'  | 'SHORT10'(!)   = ''       | ''        | 'SHORT10'   |'SHORT_R0402_M'| 'IO'  | 'JUMP.SHORT_R0402_M'            | ''     | ''             | ''          | ''            | ''   | 'KC'          | ''       
 'SM'      | 'EMPTY'  | 'SHORT14'(!)   = ''       | ''        | 'SHORT14'   |'SHORT_VIA20D10'| 'IO'  | 'JUMP.SHORT_VIA20D10'           | ''     | ''             | ''          | ''            | ''   | 'F09A-NESTOR' | ''       
 'SM'      | 'EMPTY'  | 'SHORT11'(!)   = ''       | ''        | 'SHORT11'   |'SHORT_R0603_M'| 'IO'  | 'JUMP.SHORT_R0603_M'            | ''     | ''             | ''          | ''            | ''   | ''            | ''       
 'SM'      | 'EMPTY'  | 'SHORT16'(!)   = ''       | ''        | 'SHORT16'   |'SHORT_10X12_M_FOR_INNER_LAYER'| 'IO'  | 'SHORT_10X12_M_FOR_INNER_LAYER' | ''     | ''             | ''          | ''            | ''   | ''            | ''       
 'SM'      | 'EMPTY'  | 'SHORT17'(!)   = ''       | ''        | 'SHORT17'   |'SHORT_VIA20D11-8_MSFT'| 'IO'  | 'SHORT_VIA20D11-8 FOR MSFT'     | ''     | ''             | ''          | ''            | ''   | 'S9T-AVERY'   | ''       

END_PART

END.

